# T6G (Grand Teton) — schematic netlist excerpt (pin names and nets, part order shuffled) for the footprints in the layout excerpt that follows; sources: Cadence DE-HDL packaged netlist, KiCad conversion of 04192023_DAF0TMB3IC0_F0TG_MB_C_brd_V02_OCP.brd

R3710  Q_RES  0 5% CHIP  pkg 0402LF  page 252 : A = RST_SMB_SWITCH_N ; B = PU_RST_SMB_PCIE2_N
R3559  Q_RES  0 5% CHIP  pkg 0402LF  page 237 : A = OCP_V3_2_P3V3_ADC_ALERT_R ; B = OCP_V3_2_P3V3_P12V_ADC_R_ALERT
PC492  Q_CAPP  270UF 16V 20% OSCON  pkg THLF  page 194 : A = SW_P12V_AUX_PVDDCR_CPU0_P0_FLT ; B = GND

(kicad_pcb
	(version 20260206)
	(generator "pcbnew")
	(generator_version "10.0")
	(general
		(thickness 1.6)
		(legacy_teardrops no)
	)
	(paper "A4")
	(title_block
		(title "04192023_DAF0TMB3IC0_F0TG_MB_C_brd_V02_OCP.brd")
		(comment 1 "Grand Teton / footprints 1646-1648 of 8354")
	)
	(layers
		(0 "F.Cu" signal "TOP")
		(4 "In1.Cu" signal "GND")
		(6 "In2.Cu" signal "IN1")
		(8 "In3.Cu" signal "GND1")
		(10 "In4.Cu" signal "IN2")
		(12 "In5.Cu" signal "GND2")
		(14 "In6.Cu" signal "IN3")
		(16 "In7.Cu" signal "GND3")
		(18 "In8.Cu" signal "VCC")
		(20 "In9.Cu" signal "VCC1")
		(22 "In10.Cu" signal "GND4")
		(24 "In11.Cu" signal "IN4")
		(26 "In12.Cu" signal "GND5")
		(28 "In13.Cu" signal "IN5")
		(30 "In14.Cu" signal "GND6")
		(32 "In15.Cu" signal "IN6")
		(34 "In16.Cu" signal "GND7")
		(2 "B.Cu" signal "BOTTOM")
		(9 "F.Adhes" user "F.Adhesive")
		(11 "B.Adhes" user "B.Adhesive")
		(13 "F.Paste" user "Package Geometry/Pastemask Top")
		(15 "B.Paste" user "Package Geometry/Pastemask Bottom")
		(5 "F.SilkS" user "Ref Des/Silkscreen Top")
		(7 "B.SilkS" user "Ref Des/Silkscreen Bottom")
		(1 "F.Mask" user "Board Geometry/Soldermask Top")
		(3 "B.Mask" user "Board Geometry/Soldermask Bottom")
		(17 "Dwgs.User" user "User.Drawings")
		(19 "Cmts.User" user "User.Comments")
		(21 "Eco1.User" user "User.Eco1")
		(23 "Eco2.User" user "User.Eco2")
		(25 "Edge.Cuts" user "Board Geometry/Outline")
		(27 "Margin" user)
		(31 "F.CrtYd" user "Package Geometry/Place Bound Top")
		(29 "B.CrtYd" user "Package Geometry/Place Bound Bottom")
		(35 "F.Fab" user "Ref Des/Assembly Top")
		(33 "B.Fab" user "Ref Des/Assembly Bottom")
	)
	(footprint ""
		(layer "F.Cu")
		(at 257.242056 -122.97537)
		(property "Reference" "R3710"
			(at 0 0 0)
			(layer "F.SilkS")
			(hide yes)
			(effects
				(font
					(size 1.27 1.27)
				)
			)
		)
		(property "Value" ""
			(at 0 0 0)
			(layer "F.Fab")
			(effects
				(font
					(size 1.27 1.27)
				)
			)
		)
		(duplicate_pad_numbers_are_jumpers no)
		(fp_line
			(start -0.7874 -0.4064)
			(end 0.7874 -0.4064)
			(stroke
				(width 0.1524)
				(type default)
			)
			(layer "F.SilkS")
		)
		(fp_line
			(start -0.7874 0.4064)
			(end -0.7874 -0.4064)
			(stroke
				(width 0.1524)
				(type default)
			)
			(layer "F.SilkS")
		)
		(fp_line
			(start 0.7874 -0.4064)
			(end 0.7874 0.4064)
			(stroke
				(width 0.1524)
				(type default)
			)
			(layer "F.SilkS")
		)
		(fp_line
			(start 0.7874 0.4064)
			(end -0.7874 0.4064)
			(stroke
				(width 0.1524)
				(type default)
			)
			(layer "F.SilkS")
		)
		(fp_line
			(start -0.67945 -0.305054)
			(end -0.12065 -0.305054)
			(stroke
				(width 0.1)
				(type default)
			)
			(layer "F.Fab")
		)
		(fp_line
			(start -0.67945 0.3048)
			(end -0.67945 -0.305054)
			(stroke
				(width 0.1)
				(type default)
			)
			(layer "F.Fab")
		)
		(fp_line
			(start -0.12065 -0.305054)
			(end -0.12065 -0.2794)
			(stroke
				(width 0.1)
				(type default)
			)
			(layer "F.Fab")
		)
		(fp_line
			(start -0.12065 -0.2794)
			(end 0.12065 -0.2794)
			(stroke
				(width 0.1)
				(type default)
			)
			(layer "F.Fab")
		)
		(fp_line
			(start -0.12065 0.2794)
			(end -0.12065 0.3048)
			(stroke
				(width 0.1)
				(type default)
			)
			(layer "F.Fab")
		)
		(fp_line
			(start -0.12065 0.3048)
			(end -0.67945 0.3048)
			(stroke
				(width 0.1)
				(type default)
			)
			(layer "F.Fab")
		)
		(fp_line
			(start 0.120396 0.2794)
			(end -0.12065 0.2794)
			(stroke
				(width 0.1)
				(type default)
			)
			(layer "F.Fab")
		)
		(fp_line
			(start 0.120396 0.3048)
			(end 0.120396 0.2794)
			(stroke
				(width 0.1)
				(type default)
			)
			(layer "F.Fab")
		)
		(fp_line
			(start 0.12065 -0.3048)
			(end 0.67945 -0.3048)
			(stroke
				(width 0.1)
				(type default)
			)
			(layer "F.Fab")
		)
		(fp_line
			(start 0.12065 -0.2794)
			(end 0.12065 -0.3048)
			(stroke
				(width 0.1)
				(type default)
			)
			(layer "F.Fab")
		)
		(fp_line
			(start 0.67945 -0.3048)
			(end 0.67945 0.3048)
			(stroke
				(width 0.1)
				(type default)
			)
			(layer "F.Fab")
		)
		(fp_line
			(start 0.67945 0.3048)
			(end 0.120396 0.3048)
			(stroke
				(width 0.1)
				(type default)
			)
			(layer "F.Fab")
		)
		(pad "1" smd circle
			(at -0.40005 0)
			(size 0 0)
			(layers "F.Cu" "F.Mask" "F.Paste")
			(net "RST_SMB_SWITCH_N")
		)
		(pad "2" smd circle
			(at 0.40005 0)
			(size 0 0)
			(layers "F.Cu" "F.Mask" "F.Paste")
			(net "PU_RST_SMB_PCIE2_N")
		)
	)
	(footprint ""
		(layer "F.Cu")
		(at 68.212462 -37.389562 180)
		(property "Reference" "R3559"
			(at 0 0 180)
			(layer "F.SilkS")
			(hide yes)
			(effects
				(font
					(size 1.27 1.27)
				)
			)
		)
		(property "Value" ""
			(at 0 0 180)
			(layer "F.Fab")
			(effects
				(font
					(size 1.27 1.27)
				)
			)
		)
		(duplicate_pad_numbers_are_jumpers no)
		(fp_line
			(start 0.7874 0.4064)
			(end -0.7874 0.4064)
			(stroke
				(width 0.1524)
				(type default)
			)
			(layer "F.SilkS")
		)
		(fp_line
			(start 0.7874 -0.4064)
			(end 0.7874 0.4064)
			(stroke
				(width 0.1524)
				(type default)
			)
			(layer "F.SilkS")
		)
		(fp_line
			(start -0.7874 0.4064)
			(end -0.7874 -0.4064)
			(stroke
				(width 0.1524)
				(type default)
			)
			(layer "F.SilkS")
		)
		(fp_line
			(start -0.7874 -0.4064)
			(end 0.7874 -0.4064)
			(stroke
				(width 0.1524)
				(type default)
			)
			(layer "F.SilkS")
		)
		(fp_line
			(start 0.67945 0.3048)
			(end 0.120396 0.3048)
			(stroke
				(width 0.1)
				(type default)
			)
			(layer "F.Fab")
		)
		(fp_line
			(start 0.67945 -0.3048)
			(end 0.67945 0.3048)
			(stroke
				(width 0.1)
				(type default)
			)
			(layer "F.Fab")
		)
		(fp_line
			(start 0.12065 -0.2794)
			(end 0.12065 -0.3048)
			(stroke
				(width 0.1)
				(type default)
			)
			(layer "F.Fab")
		)
		(fp_line
			(start 0.12065 -0.3048)
			(end 0.67945 -0.3048)
			(stroke
				(width 0.1)
				(type default)
			)
			(layer "F.Fab")
		)
		(fp_line
			(start 0.120396 0.3048)
			(end 0.120396 0.2794)
			(stroke
				(width 0.1)
				(type default)
			)
			(layer "F.Fab")
		)
		(fp_line
			(start 0.120396 0.2794)
			(end -0.12065 0.2794)
			(stroke
				(width 0.1)
				(type default)
			)
			(layer "F.Fab")
		)
		(fp_line
			(start -0.12065 0.3048)
			(end -0.67945 0.3048)
			(stroke
				(width 0.1)
				(type default)
			)
			(layer "F.Fab")
		)
		(fp_line
			(start -0.12065 0.2794)
			(end -0.12065 0.3048)
			(stroke
				(width 0.1)
				(type default)
			)
			(layer "F.Fab")
		)
		(fp_line
			(start -0.12065 -0.2794)
			(end 0.12065 -0.2794)
			(stroke
				(width 0.1)
				(type default)
			)
			(layer "F.Fab")
		)
		(fp_line
			(start -0.12065 -0.305054)
			(end -0.12065 -0.2794)
			(stroke
				(width 0.1)
				(type default)
			)
			(layer "F.Fab")
		)
		(fp_line
			(start -0.67945 0.3048)
			(end -0.67945 -0.305054)
			(stroke
				(width 0.1)
				(type default)
			)
			(layer "F.Fab")
		)
		(fp_line
			(start -0.67945 -0.305054)
			(end -0.12065 -0.305054)
			(stroke
				(width 0.1)
				(type default)
			)
			(layer "F.Fab")
		)
		(pad "1" smd circle
			(at -0.40005 0 180)
			(size 0 0)
			(layers "F.Cu" "F.Mask" "F.Paste")
			(net "OCP_V3_2_P3V3_ADC_ALERT_R")
		)
		(pad "2" smd circle
			(at 0.40005 0 180)
			(size 0 0)
			(layers "F.Cu" "F.Mask" "F.Paste")
			(net "OCP_V3_2_P3V3_P12V_ADC_R_ALERT")
		)
	)
	(footprint ""
		(layer "F.Cu")
		(at 359.58526 -152.71242 90)
		(property "Reference" "PC492"
			(at 4.049268 -0.80264 0)
			(unlocked yes)
			(layer "F.SilkS")
			(effects
				(font
					(size 0.7874 0.5842)
					(thickness 0.1524)
				)
				(justify left)
			)
		)
		(property "Value" ""
			(at 0 0 90)
			(layer "F.Fab")
			(effects
				(font
					(size 1.27 1.27)
				)
			)
		)
		(duplicate_pad_numbers_are_jumpers no)
		(fp_line
			(start -3.400044 1.249934)
			(end 3.400044 1.249934)
			(stroke
				(width 0.1524)
				(type default)
			)
			(layer "F.SilkS")
		)
		(fp_circle
			(center 0 1.249934)
			(end 0 4.649978)
			(stroke
				(width 0.1524)
				(type default)
			)
			(fill no)
			(layer "F.SilkS")
		)
		(fp_poly
			(pts
				(arc
					(start 3.400044 1.249934)
					(mid 0 4.649978)
					(end -3.400044 1.249934)
				)
			)
			(stroke
				(width 0)
				(type default)
			)
			(fill yes)
			(layer "F.SilkS")
		)
		(fp_circle
			(center 0 1.249934)
			(end 0 4.649978)
			(stroke
				(width 0.1)
				(type default)
			)
			(fill no)
			(layer "F.Fab")
		)
		(pad "1" thru_hole rect
			(at 0 0 90)
			(size 1.524 1.524)
			(drill 1.016)
			(layers "*.Cu" "*.Mask")
			(remove_unused_layers no)
			(net "SW_P12V_AUX_PVDDCR_CPU0_P0_FLT")
			(clearance 0)
			(padstack
				(mode front_inner_back)
				(layer "Inner"
					(shape circle)
					(size 1.524 1.524)
					(clearance 0)
				)
				(layer "B.Cu"
					(shape rect)
					(size 1.524 1.524)
					(clearance 0)
				)
			)
		)
		(pad "2" thru_hole circle
			(at 0 2.500122 90)
			(size 1.524 1.524)
			(drill 1.016)
			(layers "*.Cu" "*.Mask")
			(remove_unused_layers no)
			(net "GND")
			(clearance 0)
		)
	)
)
